# T6G (Grand Teton) — schematic netlist excerpt (pin names and nets, part order shuffled) for the footprints in the layout excerpt that follows; sources: Cadence DE-HDL packaged netlist, KiCad conversion of 04192023_DAF0TMB3IC0_F0TG_MB_C_brd_V02_OCP.brd

C561  Q_CAP  10UF 6.3V 20% X6S  pkg C0402  page 279 : A = P0V9_CPU0_RT0_2A ; B = GND
R514  Q_RES  2.2K 5% CHIP  pkg 0402LF  page 54 : A = P3V3_AUX ; B = CPU1_CORETYPE1

(kicad_pcb
	(version 20260206)
	(generator "pcbnew")
	(generator_version "10.0")
	(general
		(thickness 1.6)
		(legacy_teardrops no)
	)
	(paper "A4")
	(title_block
		(title "04192023_DAF0TMB3IC0_F0TG_MB_C_brd_V02_OCP.brd")
		(comment 1 "Grand Teton / footprints 6147-6148 of 8354")
	)
	(layers
		(0 "F.Cu" signal "TOP")
		(4 "In1.Cu" signal "GND")
		(6 "In2.Cu" signal "IN1")
		(8 "In3.Cu" signal "GND1")
		(10 "In4.Cu" signal "IN2")
		(12 "In5.Cu" signal "GND2")
		(14 "In6.Cu" signal "IN3")
		(16 "In7.Cu" signal "GND3")
		(18 "In8.Cu" signal "VCC")
		(20 "In9.Cu" signal "VCC1")
		(22 "In10.Cu" signal "GND4")
		(24 "In11.Cu" signal "IN4")
		(26 "In12.Cu" signal "GND5")
		(28 "In13.Cu" signal "IN5")
		(30 "In14.Cu" signal "GND6")
		(32 "In15.Cu" signal "IN6")
		(34 "In16.Cu" signal "GND7")
		(2 "B.Cu" signal "BOTTOM")
		(9 "F.Adhes" user "F.Adhesive")
		(11 "B.Adhes" user "B.Adhesive")
		(13 "F.Paste" user "Package Geometry/Pastemask Top")
		(15 "B.Paste" user "Package Geometry/Pastemask Bottom")
		(5 "F.SilkS" user "Ref Des/Silkscreen Top")
		(7 "B.SilkS" user "Ref Des/Silkscreen Bottom")
		(1 "F.Mask" user "Board Geometry/Soldermask Top")
		(3 "B.Mask" user "Board Geometry/Soldermask Bottom")
		(17 "Dwgs.User" user "User.Drawings")
		(19 "Cmts.User" user "User.Comments")
		(21 "Eco1.User" user "User.Eco1")
		(23 "Eco2.User" user "User.Eco2")
		(25 "Edge.Cuts" user "Board Geometry/Outline")
		(27 "Margin" user)
		(31 "F.CrtYd" user "Package Geometry/Place Bound Top")
		(29 "B.CrtYd" user "Package Geometry/Place Bound Bottom")
		(35 "F.Fab" user "Ref Des/Assembly Top")
		(33 "B.Fab" user "Ref Des/Assembly Bottom")
	)
	(footprint ""
		(layer "B.Cu")
		(at 63.619634 -196.186552 180)
		(property "Reference" "R514"
			(at 0 0 0)
			(layer "B.SilkS")
			(hide yes)
			(effects
				(font
					(size 1.27 1.27)
				)
				(justify mirror)
			)
		)
		(property "Value" ""
			(at 0 0 0)
			(layer "B.Fab")
			(effects
				(font
					(size 1.27 1.27)
				)
				(justify mirror)
			)
		)
		(duplicate_pad_numbers_are_jumpers no)
		(fp_line
			(start 0.7874 0.4064)
			(end 0.7874 -0.4064)
			(stroke
				(width 0.1524)
				(type default)
			)
			(layer "B.SilkS")
		)
		(fp_line
			(start 0.7874 -0.4064)
			(end -0.7874 -0.4064)
			(stroke
				(width 0.1524)
				(type default)
			)
			(layer "B.SilkS")
		)
		(fp_line
			(start -0.7874 0.4064)
			(end 0.7874 0.4064)
			(stroke
				(width 0.1524)
				(type default)
			)
			(layer "B.SilkS")
		)
		(fp_line
			(start -0.7874 -0.4064)
			(end -0.7874 0.4064)
			(stroke
				(width 0.1524)
				(type default)
			)
			(layer "B.SilkS")
		)
		(fp_line
			(start 0.67945 0.3048)
			(end 0.67945 -0.305054)
			(stroke
				(width 0.1)
				(type default)
			)
			(layer "B.Fab")
		)
		(fp_line
			(start 0.67945 -0.305054)
			(end 0.12065 -0.305054)
			(stroke
				(width 0.1)
				(type default)
			)
			(layer "B.Fab")
		)
		(fp_line
			(start 0.12065 0.3048)
			(end 0.67945 0.3048)
			(stroke
				(width 0.1)
				(type default)
			)
			(layer "B.Fab")
		)
		(fp_line
			(start 0.12065 0.2794)
			(end 0.12065 0.3048)
			(stroke
				(width 0.1)
				(type default)
			)
			(layer "B.Fab")
		)
		(fp_line
			(start 0.12065 -0.2794)
			(end -0.12065 -0.2794)
			(stroke
				(width 0.1)
				(type default)
			)
			(layer "B.Fab")
		)
		(fp_line
			(start 0.12065 -0.305054)
			(end 0.12065 -0.2794)
			(stroke
				(width 0.1)
				(type default)
			)
			(layer "B.Fab")
		)
		(fp_line
			(start -0.120396 0.3048)
			(end -0.120396 0.2794)
			(stroke
				(width 0.1)
				(type default)
			)
			(layer "B.Fab")
		)
		(fp_line
			(start -0.120396 0.2794)
			(end 0.12065 0.2794)
			(stroke
				(width 0.1)
				(type default)
			)
			(layer "B.Fab")
		)
		(fp_line
			(start -0.12065 -0.2794)
			(end -0.12065 -0.3048)
			(stroke
				(width 0.1)
				(type default)
			)
			(layer "B.Fab")
		)
		(fp_line
			(start -0.12065 -0.3048)
			(end -0.67945 -0.3048)
			(stroke
				(width 0.1)
				(type default)
			)
			(layer "B.Fab")
		)
		(fp_line
			(start -0.67945 0.3048)
			(end -0.120396 0.3048)
			(stroke
				(width 0.1)
				(type default)
			)
			(layer "B.Fab")
		)
		(fp_line
			(start -0.67945 -0.3048)
			(end -0.67945 0.3048)
			(stroke
				(width 0.1)
				(type default)
			)
			(layer "B.Fab")
		)
		(pad "1" smd circle
			(at 0.40005 0)
			(size 0 0)
			(layers "B.Cu" "B.Mask" "B.Paste")
			(net "P3V3_AUX")
		)
		(pad "2" smd circle
			(at -0.40005 0)
			(size 0 0)
			(layers "B.Cu" "B.Mask" "B.Paste")
			(net "CPU1_CORETYPE1")
		)
	)
	(footprint ""
		(layer "B.Cu")
		(at 303.390808 -398.942052 90)
		(property "Reference" "C561"
			(at 0 0 90)
			(layer "B.SilkS")
			(hide yes)
			(effects
				(font
					(size 1.27 1.27)
				)
				(justify mirror)
			)
		)
		(property "Value" ""
			(at 0 0 90)
			(layer "B.Fab")
			(effects
				(font
					(size 1.27 1.27)
				)
				(justify mirror)
			)
		)
		(duplicate_pad_numbers_are_jumpers no)
		(fp_line
			(start 0.7874 -0.4064)
			(end -0.7874 -0.4064)
			(stroke
				(width 0.1524)
				(type default)
			)
			(layer "B.SilkS")
		)
		(fp_line
			(start -0.7874 -0.4064)
			(end -0.7874 0.4064)
			(stroke
				(width 0.1524)
				(type default)
			)
			(layer "B.SilkS")
		)
		(fp_line
			(start 0.7874 0.4064)
			(end 0.7874 -0.4064)
			(stroke
				(width 0.1524)
				(type default)
			)
			(layer "B.SilkS")
		)
		(fp_line
			(start -0.7874 0.4064)
			(end 0.7874 0.4064)
			(stroke
				(width 0.1524)
				(type default)
			)
			(layer "B.SilkS")
		)
		(fp_line
			(start 0.67945 -0.305054)
			(end 0.12065 -0.305054)
			(stroke
				(width 0.1)
				(type default)
			)
			(layer "B.Fab")
		)
		(fp_line
			(start 0.12065 -0.305054)
			(end 0.12065 -0.2794)
			(stroke
				(width 0.1)
				(type default)
			)
			(layer "B.Fab")
		)
		(fp_line
			(start -0.12065 -0.3048)
			(end -0.67945 -0.3048)
			(stroke
				(width 0.1)
				(type default)
			)
			(layer "B.Fab")
		)
		(fp_line
			(start -0.67945 -0.3048)
			(end -0.67945 0.3048)
			(stroke
				(width 0.1)
				(type default)
			)
			(layer "B.Fab")
		)
		(fp_line
			(start 0.12065 -0.2794)
			(end -0.12065 -0.2794)
			(stroke
				(width 0.1)
				(type default)
			)
			(layer "B.Fab")
		)
		(fp_line
			(start -0.12065 -0.2794)
			(end -0.12065 -0.3048)
			(stroke
				(width 0.1)
				(type default)
			)
			(layer "B.Fab")
		)
		(fp_line
			(start 0.12065 0.2794)
			(end 0.12065 0.3048)
			(stroke
				(width 0.1)
				(type default)
			)
			(layer "B.Fab")
		)
		(fp_line
			(start -0.120396 0.2794)
			(end 0.12065 0.2794)
			(stroke
				(width 0.1)
				(type default)
			)
			(layer "B.Fab")
		)
		(fp_line
			(start 0.67945 0.3048)
			(end 0.67945 -0.305054)
			(stroke
				(width 0.1)
				(type default)
			)
			(layer "B.Fab")
		)
		(fp_line
			(start 0.12065 0.3048)
			(end 0.67945 0.3048)
			(stroke
				(width 0.1)
				(type default)
			)
			(layer "B.Fab")
		)
		(fp_line
			(start -0.120396 0.3048)
			(end -0.120396 0.2794)
			(stroke
				(width 0.1)
				(type default)
			)
			(layer "B.Fab")
		)
		(fp_line
			(start -0.67945 0.3048)
			(end -0.120396 0.3048)
			(stroke
				(width 0.1)
				(type default)
			)
			(layer "B.Fab")
		)
		(pad "1" smd circle
			(at 0.40005 0 270)
			(size 0 0)
			(layers "B.Cu" "B.Mask" "B.Paste")
			(net "P0V9_CPU0_RT0_2A")
		)
		(pad "2" smd circle
			(at -0.40005 0 270)
			(size 0 0)
			(layers "B.Cu" "B.Mask" "B.Paste")
			(net "GND")
		)
	)
)
